# BASEBOARD_FAB2 (Tioga Pass) — schematic netlist excerpt (pin names and nets, part order shuffled) for the footprints in the layout excerpt that follows; sources: Cadence DE-HDL packaged netlist, KiCad conversion of Wiwynn_Tioga_Pass_MB.brd

CR30W1  DIODEAC_DUAL_ARRAY  ESD3V3U4ULC IC  pkg SM9  page 253
  AC0  = USB3_P01_FB_TXN
  AC1  = USB3_P01_FB_TXP
  GND(0)  = GND
  AC2  = USB3_P01_FB_RXN
  AC3  = USB3_P01_FB_RXP
  OUT3  = USB3_P01_FB_RXP
  OUT2  = USB3_P01_FB_RXN
  OUT1  = USB3_P01_FB_TXP
  OUT0  = USB3_P01_FB_TXN

R2T54  RES  665 1.0% CHIP  pkg 0402  page 138 : A = P3V3_STBY ; B = SMB_BMC_PMBUS_STBY_LVC3_SCL
R1T2  RES  665 1.0% CHIP  pkg 0402  page 160 : A = P3V3_STBY ; B = SMB_SLOTX24_STBY_LVC3_SCL_R

(kicad_pcb
	(version 20260206)
	(generator "pcbnew")
	(generator_version "10.0")
	(general
		(thickness 1.6)
		(legacy_teardrops no)
	)
	(paper "A4")
	(title_block
		(title "Wiwynn_Tioga_Pass_MB.brd")
		(comment 1 "Tioga Pass / footprints 3459-3461 of 4770")
	)
	(layers
		(0 "F.Cu" signal "TOP")
		(4 "In1.Cu" signal "L2GND")
		(6 "In2.Cu" signal "L3")
		(8 "In3.Cu" signal "L4GND")
		(10 "In4.Cu" signal "L5")
		(12 "In5.Cu" signal "L6GND")
		(14 "In6.Cu" signal "L7VCC")
		(16 "In7.Cu" signal "L8VCC")
		(18 "In8.Cu" signal "L9GND")
		(20 "In9.Cu" signal "L10")
		(22 "In10.Cu" signal "L11GND")
		(24 "In11.Cu" signal "L12")
		(26 "In12.Cu" signal "L13GND")
		(2 "B.Cu" signal "BOTTOM")
		(9 "F.Adhes" user "F.Adhesive")
		(11 "B.Adhes" user "B.Adhesive")
		(13 "F.Paste" user "Package Geometry/Pastemask Top")
		(15 "B.Paste" user "Package Geometry/Pastemask Bottom")
		(5 "F.SilkS" user "Ref Des/Silkscreen Top")
		(7 "B.SilkS" user "Ref Des/Silkscreen Bottom")
		(1 "F.Mask" user "Board Geometry/Soldermask Top")
		(3 "B.Mask" user "Board Geometry/Soldermask Bottom")
		(17 "Dwgs.User" user "User.Drawings")
		(19 "Cmts.User" user "User.Comments")
		(21 "Eco1.User" user "User.Eco1")
		(23 "Eco2.User" user "User.Eco2")
		(25 "Edge.Cuts" user "Board Geometry/Outline")
		(27 "Margin" user)
		(31 "F.CrtYd" user "Package Geometry/Place Bound Top")
		(29 "B.CrtYd" user "Package Geometry/Place Bound Bottom")
		(35 "F.Fab" user "Ref Des/Assembly Top")
		(33 "B.Fab" user "Ref Des/Assembly Bottom")
	)
	(footprint ""
		(layer "B.Cu")
		(at 491.925864 -55.880762 -90)
		(property "Reference" "CR30W1"
			(at 1.495806 -1.067816 270)
			(unlocked yes)
			(layer "B.SilkS")
			(effects
				(font
					(size 0.4064 0.254)
					(thickness 0.1524)
				)
				(justify left mirror)
			)
		)
		(property "Value" ""
			(at 0 0 90)
			(layer "B.Fab")
			(effects
				(font
					(size 1.27 1.27)
				)
				(justify mirror)
			)
		)
		(duplicate_pad_numbers_are_jumpers no)
		(fp_circle
			(center 0.589026 -0.5334)
			(end 0.589026 -0.6604)
			(stroke
				(width 0.254)
				(type default)
			)
			(fill no)
			(layer "B.SilkS")
		)
		(fp_rect
			(start 0.225552 2.167382)
			(end -0.809498 -0.167386)
			(stroke
				(width 0)
				(type default)
			)
			(fill no)
			(layer "B.CrtYd")
		)
		(fp_line
			(start -0.809498 2.167382)
			(end 0.225552 2.167382)
			(stroke
				(width 0.1)
				(type default)
			)
			(layer "B.Fab")
		)
		(fp_line
			(start 0.225552 2.167382)
			(end 0.225552 -0.167386)
			(stroke
				(width 0.1)
				(type default)
			)
			(layer "B.Fab")
		)
		(fp_line
			(start -0.809498 -0.167386)
			(end -0.809498 2.167382)
			(stroke
				(width 0.1)
				(type default)
			)
			(layer "B.Fab")
		)
		(fp_line
			(start 0.225552 -0.167386)
			(end -0.809498 -0.167386)
			(stroke
				(width 0.1)
				(type default)
			)
			(layer "B.Fab")
		)
		(fp_circle
			(center 0.589026 -0.5334)
			(end 0.589026 -0.6604)
			(stroke
				(width 0.254)
				(type default)
			)
			(fill no)
			(layer "B.Fab")
		)
		(pad "1" smd rect
			(at 0 0 90)
			(size 0.3556 0.2032)
			(layers "B.Cu" "B.Mask" "B.Paste")
			(net "USB3_P01_FB_TXN")
		)
		(pad "2" smd rect
			(at 0 0.500126 90)
			(size 0.3556 0.2032)
			(layers "B.Cu" "B.Mask" "B.Paste")
			(net "USB3_P01_FB_TXP")
		)
		(pad "3" smd rect
			(at -0.2921 0.999998 90)
			(size 0.9398 0.4064)
			(layers "B.Cu" "B.Mask" "B.Paste")
			(net "GND")
		)
		(pad "4" smd rect
			(at 0 1.500124 90)
			(size 0.3556 0.2032)
			(layers "B.Cu" "B.Mask" "B.Paste")
			(net "USB3_P01_FB_RXN")
		)
		(pad "5" smd rect
			(at 0 1.999996 90)
			(size 0.3556 0.2032)
			(layers "B.Cu" "B.Mask" "B.Paste")
			(net "USB3_P01_FB_RXP")
		)
		(pad "6" smd rect
			(at -0.583946 1.999996 90)
			(size 0.3556 0.2032)
			(layers "B.Cu" "B.Mask" "B.Paste")
			(net "USB3_P01_FB_RXP")
		)
		(pad "7" smd rect
			(at -0.583946 1.500124 90)
			(size 0.3556 0.2032)
			(layers "B.Cu" "B.Mask" "B.Paste")
			(net "USB3_P01_FB_RXN")
		)
		(pad "8" smd rect
			(at -0.583946 0.500126 90)
			(size 0.3556 0.2032)
			(layers "B.Cu" "B.Mask" "B.Paste")
			(net "USB3_P01_FB_TXP")
		)
		(pad "9" smd rect
			(at -0.583946 0 90)
			(size 0.3556 0.2032)
			(layers "B.Cu" "B.Mask" "B.Paste")
			(net "USB3_P01_FB_TXN")
		)
	)
	(footprint ""
		(layer "B.Cu")
		(at 402.59 -73.406 180)
		(property "Reference" "R2T54"
			(at 0 0 0)
			(layer "B.SilkS")
			(hide yes)
			(effects
				(font
					(size 1.27 1.27)
				)
				(justify mirror)
			)
		)
		(property "Value" ""
			(at 0 0 0)
			(layer "B.Fab")
			(effects
				(font
					(size 1.27 1.27)
				)
				(justify mirror)
			)
		)
		(duplicate_pad_numbers_are_jumpers no)
		(fp_poly
			(pts
				(xy 0.2794 -0.1016) (xy -0.2794 -0.1016) (xy -0.2794 0.9906) (xy 0.2794 0.9906)
			)
			(stroke
				(width 0)
				(type default)
			)
			(fill no)
			(layer "B.CrtYd")
		)
		(fp_line
			(start 0.2794 0.9906)
			(end -0.2794 0.9906)
			(stroke
				(width 0.1)
				(type default)
			)
			(layer "B.Fab")
		)
		(fp_line
			(start 0.2794 -0.1016)
			(end 0.2794 0.9906)
			(stroke
				(width 0.1)
				(type default)
			)
			(layer "B.Fab")
		)
		(fp_line
			(start -0.2794 0.9906)
			(end -0.2794 -0.1016)
			(stroke
				(width 0.1)
				(type default)
			)
			(layer "B.Fab")
		)
		(fp_line
			(start -0.2794 -0.1016)
			(end 0.2794 -0.1016)
			(stroke
				(width 0.1)
				(type default)
			)
			(layer "B.Fab")
		)
		(pad "1" smd rect
			(at 0 0)
			(size 0.508 0.508)
			(layers "B.Cu" "B.Mask" "B.Paste")
			(net "P3V3_STBY")
		)
		(pad "2" smd rect
			(at 0 0.889)
			(size 0.508 0.508)
			(layers "B.Cu" "B.Mask" "B.Paste")
			(net "SMB_BMC_PMBUS_STBY_LVC3_SCL")
		)
		(zone
			(layer "B.Cu")
			(hatch none 0.5)
			(connect_pads
				(clearance 0)
			)
			(min_thickness 0.25)
			(keepout
				(tracks not_allowed)
				(vias allowed)
				(pads allowed)
				(copperpour not_allowed)
				(footprints allowed)
			)
			(placement
				(enabled no)
				(sheetname "")
			)
			(fill
				(thermal_gap 0.5)
				(thermal_bridge_width 0.5)
				(island_removal_mode 0)
			)
			(polygon
				(pts
					(xy 402.336 -74.041) (xy 402.844 -74.041) (xy 402.844 -73.66) (xy 402.336 -73.66)
				)
			)
		)
		(zone
			(layer "B.Cu")
			(hatch none 0.5)
			(connect_pads
				(clearance 0)
			)
			(min_thickness 0.25)
			(keepout
				(tracks allowed)
				(vias not_allowed)
				(pads allowed)
				(copperpour not_allowed)
				(footprints allowed)
			)
			(placement
				(enabled no)
				(sheetname "")
			)
			(fill
				(thermal_gap 0.5)
				(thermal_bridge_width 0.5)
				(island_removal_mode 0)
			)
			(polygon
				(pts
					(xy 402.336 -73.66) (xy 402.844 -73.66) (xy 402.844 -74.041) (xy 402.336 -74.041)
				)
			)
		)
	)
	(footprint ""
		(layer "B.Cu")
		(at 418.7063 -48.1584 -90)
		(property "Reference" "R1T2"
			(at 0 0 90)
			(layer "B.SilkS")
			(hide yes)
			(effects
				(font
					(size 1.27 1.27)
				)
				(justify mirror)
			)
		)
		(property "Value" ""
			(at 0 0 90)
			(layer "B.Fab")
			(effects
				(font
					(size 1.27 1.27)
				)
				(justify mirror)
			)
		)
		(duplicate_pad_numbers_are_jumpers no)
		(fp_poly
			(pts
				(xy 0.2794 -0.1016) (xy -0.2794 -0.1016) (xy -0.2794 0.9906) (xy 0.2794 0.9906)
			)
			(stroke
				(width 0)
				(type default)
			)
			(fill no)
			(layer "B.CrtYd")
		)
		(fp_line
			(start -0.2794 0.9906)
			(end -0.2794 -0.1016)
			(stroke
				(width 0.1)
				(type default)
			)
			(layer "B.Fab")
		)
		(fp_line
			(start 0.2794 0.9906)
			(end -0.2794 0.9906)
			(stroke
				(width 0.1)
				(type default)
			)
			(layer "B.Fab")
		)
		(fp_line
			(start -0.2794 -0.1016)
			(end 0.2794 -0.1016)
			(stroke
				(width 0.1)
				(type default)
			)
			(layer "B.Fab")
		)
		(fp_line
			(start 0.2794 -0.1016)
			(end 0.2794 0.9906)
			(stroke
				(width 0.1)
				(type default)
			)
			(layer "B.Fab")
		)
		(pad "1" smd rect
			(at 0 0 90)
			(size 0.508 0.508)
			(layers "B.Cu" "B.Mask" "B.Paste")
			(net "P3V3_STBY")
		)
		(pad "2" smd rect
			(at 0 0.889 90)
			(size 0.508 0.508)
			(layers "B.Cu" "B.Mask" "B.Paste")
			(net "SMB_SLOTX24_STBY_LVC3_SCL_R")
		)
		(zone
			(layer "B.Cu")
			(hatch none 0.5)
			(connect_pads
				(clearance 0)
			)
			(min_thickness 0.25)
			(keepout
				(tracks not_allowed)
				(vias allowed)
				(pads allowed)
				(copperpour not_allowed)
				(footprints allowed)
			)
			(placement
				(enabled no)
				(sheetname "")
			)
			(fill
				(thermal_gap 0.5)
				(thermal_bridge_width 0.5)
				(island_removal_mode 0)
			)
			(polygon
				(pts
					(xy 418.0713 -47.9044) (xy 418.0713 -48.4124) (xy 418.4523 -48.4124) (xy 418.4523 -47.9044)
				)
			)
		)
		(zone
			(layer "B.Cu")
			(hatch none 0.5)
			(connect_pads
				(clearance 0)
			)
			(min_thickness 0.25)
			(keepout
				(tracks allowed)
				(vias not_allowed)
				(pads allowed)
				(copperpour not_allowed)
				(footprints allowed)
			)
			(placement
				(enabled no)
				(sheetname "")
			)
			(fill
				(thermal_gap 0.5)
				(thermal_bridge_width 0.5)
				(island_removal_mode 0)
			)
			(polygon
				(pts
					(xy 418.4523 -47.9044) (xy 418.4523 -48.4124) (xy 418.0713 -48.4124) (xy 418.0713 -47.9044)
				)
			)
		)
	)
)
